# SCM (Grand Teton) — schematic netlist excerpt (pin names and nets, part order shuffled) for the footprints in the layout excerpt that follows; sources: Cadence DE-HDL packaged netlist, KiCad conversion of 12092022_DA0F0TMDCD0_F0T_Management_Board_D_brd_V3_OCP.brd

R566  Q_RES  0 5% CHIP  pkg 0402LF  page 15 : A = RST_BMC_RSTBTN_OUT_R_N ; B = RST_BMC_RSTBTN_OUT_N
L9  Q_INDUCTOR  BLM18PG121SN1D/2000MA EMPTY  pkg SMLF  page 17 : \1\ = P3V3_AUX ; \2\ = P3V3_STBY_PLLAHVDD

(kicad_pcb
	(version 20260206)
	(generator "pcbnew")
	(generator_version "10.0")
	(general
		(thickness 1.6)
		(legacy_teardrops no)
	)
	(paper "A4")
	(title_block
		(title "12092022_DA0F0TMDCD0_F0T_Management_Board_D_brd_V3_OCP.brd")
		(comment 1 "Grand Teton / footprints 1357-1358 of 1440")
	)
	(layers
		(0 "F.Cu" signal "TOP")
		(4 "In1.Cu" signal "GND")
		(6 "In2.Cu" signal "IN1")
		(8 "In3.Cu" signal "GND1")
		(10 "In4.Cu" signal "IN2")
		(12 "In5.Cu" signal "VCC")
		(14 "In6.Cu" signal "VCC1")
		(16 "In7.Cu" signal "IN3")
		(18 "In8.Cu" signal "GND2")
		(20 "In9.Cu" signal "IN4")
		(22 "In10.Cu" signal "GND3")
		(2 "B.Cu" signal "BOTTOM")
		(9 "F.Adhes" user "F.Adhesive")
		(11 "B.Adhes" user "B.Adhesive")
		(13 "F.Paste" user "Package Geometry/Pastemask Top")
		(15 "B.Paste" user "Package Geometry/Pastemask Bottom")
		(5 "F.SilkS" user "Ref Des/Silkscreen Top")
		(7 "B.SilkS" user "Ref Des/Silkscreen Bottom")
		(1 "F.Mask" user "Board Geometry/Soldermask Top")
		(3 "B.Mask" user "Board Geometry/Soldermask Bottom")
		(17 "Dwgs.User" user "User.Drawings")
		(19 "Cmts.User" user "User.Comments")
		(21 "Eco1.User" user "User.Eco1")
		(23 "Eco2.User" user "User.Eco2")
		(25 "Edge.Cuts" user "Board Geometry/Outline")
		(27 "Margin" user)
		(31 "F.CrtYd" user "Package Geometry/Place Bound Top")
		(29 "B.CrtYd" user "Package Geometry/Place Bound Bottom")
		(35 "F.Fab" user "Ref Des/Assembly Top")
		(33 "B.Fab" user "Ref Des/Assembly Bottom")
	)
	(footprint ""
		(layer "B.Cu")
		(at 34.925 -32.004 -90)
		(property "Reference" "L9"
			(at 0 0 90)
			(layer "B.SilkS")
			(hide yes)
			(effects
				(font
					(size 1.27 1.27)
				)
				(justify mirror)
			)
		)
		(property "Value" ""
			(at 0 0 90)
			(layer "B.Fab")
			(effects
				(font
					(size 1.27 1.27)
				)
				(justify mirror)
			)
		)
		(duplicate_pad_numbers_are_jumpers no)
		(fp_line
			(start -1.27 0.5842)
			(end 1.27 0.5842)
			(stroke
				(width 0.1524)
				(type default)
			)
			(layer "B.SilkS")
		)
		(fp_line
			(start -1.27 0.5842)
			(end -1.27 -0.5842)
			(stroke
				(width 0.1524)
				(type default)
			)
			(layer "B.SilkS")
		)
		(fp_line
			(start -0.127 0.5842)
			(end -0.127 -0.5842)
			(stroke
				(width 0.1524)
				(type default)
			)
			(layer "B.SilkS")
		)
		(fp_line
			(start 0.127 0.5842)
			(end 0.127 -0.5842)
			(stroke
				(width 0.1524)
				(type default)
			)
			(layer "B.SilkS")
		)
		(fp_line
			(start 1.27 0.5842)
			(end 1.27 -0.5842)
			(stroke
				(width 0.1524)
				(type default)
			)
			(layer "B.SilkS")
		)
		(fp_line
			(start 1.27 -0.5588)
			(end 1.27 -0.5842)
			(stroke
				(width 0.1524)
				(type default)
			)
			(layer "B.SilkS")
		)
		(fp_line
			(start 1.27 -0.5842)
			(end -1.27 -0.5842)
			(stroke
				(width 0.1524)
				(type default)
			)
			(layer "B.SilkS")
		)
		(fp_line
			(start -0.9144 0.508)
			(end 0.9144 0.508)
			(stroke
				(width 0.1)
				(type default)
			)
			(layer "B.Fab")
		)
		(fp_line
			(start 0.9144 0.508)
			(end 0.9144 0.406654)
			(stroke
				(width 0.1)
				(type default)
			)
			(layer "B.Fab")
		)
		(fp_line
			(start 0.9144 0.406654)
			(end 1.194308 0.406654)
			(stroke
				(width 0.1)
				(type default)
			)
			(layer "B.Fab")
		)
		(fp_line
			(start 1.194308 0.406654)
			(end 1.194308 -0.406654)
			(stroke
				(width 0.1)
				(type default)
			)
			(layer "B.Fab")
		)
		(fp_line
			(start -1.1938 0.4064)
			(end -0.9144 0.4064)
			(stroke
				(width 0.1)
				(type default)
			)
			(layer "B.Fab")
		)
		(fp_line
			(start -0.9144 0.4064)
			(end -0.9144 0.508)
			(stroke
				(width 0.1)
				(type default)
			)
			(layer "B.Fab")
		)
		(fp_line
			(start -1.1938 -0.406654)
			(end -1.1938 0.4064)
			(stroke
				(width 0.1)
				(type default)
			)
			(layer "B.Fab")
		)
		(fp_line
			(start -0.9144 -0.406654)
			(end -1.1938 -0.406654)
			(stroke
				(width 0.1)
				(type default)
			)
			(layer "B.Fab")
		)
		(fp_line
			(start 0.9144 -0.406654)
			(end 0.9144 -0.508)
			(stroke
				(width 0.1)
				(type default)
			)
			(layer "B.Fab")
		)
		(fp_line
			(start 1.194308 -0.406654)
			(end 0.9144 -0.406654)
			(stroke
				(width 0.1)
				(type default)
			)
			(layer "B.Fab")
		)
		(fp_line
			(start -0.9144 -0.508)
			(end -0.9144 -0.406654)
			(stroke
				(width 0.1)
				(type default)
			)
			(layer "B.Fab")
		)
		(fp_line
			(start 0.9144 -0.508)
			(end -0.9144 -0.508)
			(stroke
				(width 0.1)
				(type default)
			)
			(layer "B.Fab")
		)
		(pad "1" smd rect
			(at 0.7366 0 180)
			(size 0.7112 0.8128)
			(layers "B.Cu" "B.Mask" "B.Paste")
			(net "P3V3_AUX")
		)
		(pad "2" smd rect
			(at -0.7366 0 180)
			(size 0.7112 0.8128)
			(layers "B.Cu" "B.Mask" "B.Paste")
			(net "P3V3_STBY_PLLAHVDD")
		)
	)
	(footprint ""
		(layer "B.Cu")
		(at 40.4114 -58.097928)
		(property "Reference" "R566"
			(at 0 0 0)
			(layer "B.SilkS")
			(hide yes)
			(effects
				(font
					(size 1.27 1.27)
				)
				(justify mirror)
			)
		)
		(property "Value" ""
			(at 0 0 0)
			(layer "B.Fab")
			(effects
				(font
					(size 1.27 1.27)
				)
				(justify mirror)
			)
		)
		(duplicate_pad_numbers_are_jumpers no)
		(fp_line
			(start -0.7874 -0.4064)
			(end -0.7874 0.4064)
			(stroke
				(width 0.1524)
				(type default)
			)
			(layer "B.SilkS")
		)
		(fp_line
			(start -0.7874 0.4064)
			(end 0.7874 0.4064)
			(stroke
				(width 0.1524)
				(type default)
			)
			(layer "B.SilkS")
		)
		(fp_line
			(start 0.7874 -0.4064)
			(end -0.7874 -0.4064)
			(stroke
				(width 0.1524)
				(type default)
			)
			(layer "B.SilkS")
		)
		(fp_line
			(start 0.7874 0.4064)
			(end 0.7874 -0.4064)
			(stroke
				(width 0.1524)
				(type default)
			)
			(layer "B.SilkS")
		)
		(fp_line
			(start -0.67945 -0.3048)
			(end -0.67945 0.3048)
			(stroke
				(width 0.1)
				(type default)
			)
			(layer "B.Fab")
		)
		(fp_line
			(start -0.67945 0.3048)
			(end -0.120396 0.3048)
			(stroke
				(width 0.1)
				(type default)
			)
			(layer "B.Fab")
		)
		(fp_line
			(start -0.12065 -0.3048)
			(end -0.67945 -0.3048)
			(stroke
				(width 0.1)
				(type default)
			)
			(layer "B.Fab")
		)
		(fp_line
			(start -0.12065 -0.2794)
			(end -0.12065 -0.3048)
			(stroke
				(width 0.1)
				(type default)
			)
			(layer "B.Fab")
		)
		(fp_line
			(start -0.120396 0.2794)
			(end 0.12065 0.2794)
			(stroke
				(width 0.1)
				(type default)
			)
			(layer "B.Fab")
		)
		(fp_line
			(start -0.120396 0.3048)
			(end -0.120396 0.2794)
			(stroke
				(width 0.1)
				(type default)
			)
			(layer "B.Fab")
		)
		(fp_line
			(start 0.12065 -0.305054)
			(end 0.12065 -0.2794)
			(stroke
				(width 0.1)
				(type default)
			)
			(layer "B.Fab")
		)
		(fp_line
			(start 0.12065 -0.2794)
			(end -0.12065 -0.2794)
			(stroke
				(width 0.1)
				(type default)
			)
			(layer "B.Fab")
		)
		(fp_line
			(start 0.12065 0.2794)
			(end 0.12065 0.3048)
			(stroke
				(width 0.1)
				(type default)
			)
			(layer "B.Fab")
		)
		(fp_line
			(start 0.12065 0.3048)
			(end 0.67945 0.3048)
			(stroke
				(width 0.1)
				(type default)
			)
			(layer "B.Fab")
		)
		(fp_line
			(start 0.67945 -0.305054)
			(end 0.12065 -0.305054)
			(stroke
				(width 0.1)
				(type default)
			)
			(layer "B.Fab")
		)
		(fp_line
			(start 0.67945 0.3048)
			(end 0.67945 -0.305054)
			(stroke
				(width 0.1)
				(type default)
			)
			(layer "B.Fab")
		)
		(pad "1" smd circle
			(at 0.40005 0 180)
			(size 0 0)
			(layers "B.Cu" "B.Mask" "B.Paste")
			(net "RST_BMC_RSTBTN_OUT_R_N")
		)
		(pad "2" smd circle
			(at -0.40005 0 180)
			(size 0 0)
			(layers "B.Cu" "B.Mask" "B.Paste")
			(net "RST_BMC_RSTBTN_OUT_N")
		)
	)
)
